FILE_TYPE = MACRO_DRAWING;
SET COLOR_WIRE YELLOW;
SET COLOR_PROP ORANGE;
SET COLOR_DOT WHITE;
SET COLOR_ARC YELLOW;
SET COLOR_BODY GREEN;
SET COLOR_NOTE PURPLE;
SET PROP_DISPLAY VALUE;
SET PAGE_NUMBER P5;
FORCEADD QUANTA_TITLE_BLOCK_C..1
(5775 -1350);
FORCEPROP 1 LAST CUSTOM_TXT_CDS <NAME_2>
J 0
(2600 -1300);
FORCEPROP 1 LAST CUSTOM_TXT_CDS <NAME_1>
J 0
(2600 -1175);
FORCEPROP 1 LAST CUSTOM_TXT_CDS <Q_NUMBER>
J 0
(4372 -1247);
DISPLAY 1.212766 (4372 -1247);
FORCEPROP 1 LAST CUSTOM_TXT_CDS <Q_PROJ>
J 0
(3393 -1248);
DISPLAY 1.212766 (3393 -1248);
FORCEPROP 1 LAST CUSTOM_TXT_CDS <Q_REV>
J 0
(5591 -1247);
DISPLAY 1.212766 (5591 -1247);
FORCEPROP 1 LAST CUSTOM_TXT_CDS <CON_LAST_MODIFIED>
J 0
(3890 -1335);
DISPLAY 0.978723 (3890 -1335);
FORCEPROP 1 LAST CUSTOM_TXT_CDS <CON_PAGE_NUM> OF <CON_TOTAL_PAGES>
J 0
(5329 -1332);
DISPLAY 0.978723 (5329 -1332);
FORCEPROP 1 LAST Q_TITLE BLOCK DIAGRAM - MB
J 0
(-3591 -1324);
DISPLAY 2.446809 (-3591 -1324);
PAINT GREEN (-3591 -1324);
FORCEPROP 1 LAST Q_DEPT 
J 1
(2012 -1301);
DISPLAY 1.957447 (2012 -1301);
PAINT GREEN (2012 -1301);
FORCEPROP 2 LAST CDS_LIB pure_quanta
J 0
(5775 -1350);
PAINT MONO (5775 -1350);
DISPLAY INVISIBLE (5775 -1350);
FORCEPROP 1 LAST CDS_LMAN_SYM_OUTLINE -9475,6775,100,-125
J 0
(5775 -1350);
DISPLAY 0.468085 (5775 -1350);
PAINT GREEN (5775 -1350);
DISPLAY INVISIBLE (5775 -1350);
FORCEPROP 1 LAST COMMENT_BODY TRUE
J 0
(5787 -1363);
DISPLAY 0.978723 (5787 -1363);
PAINT GREEN (5787 -1363);
DISPLAY INVISIBLE (5787 -1363);
FORCEPROP 2 LAST PAGE_BORDER TRUE
J 0
(-2115 3900);
DISPLAY 0.638298 (-2115 3900);
PAINT PINK (-2115 3900);
DISPLAY INVISIBLE (-2115 3900);
FORCEPROP 2 LAST CDS_XR_PAGE_TITLE CR-5 : @S9S_MB_2U_LIB.S9S_MB_2U(SCH_1):PAGE5
J 0
(-2115 3900);
DISPLAY 0.638298 (-2115 3900);
PAINT PINK (-2115 3900);
DISPLAY INVISIBLE (-2115 3900);
FORCEPROP 2 LAST CUSTOM_TXT_CDS <XR_PAGE_TITLE>
J 0
(-2115 3900);
DISPLAY 0.638298 (-2115 3900);
PAINT PINK (-2115 3900);
DISPLAY INVISIBLE (-2115 3900);
FORCEPROP 0 LAST CDS_CON_LAST_MODIFIED Thu Aug 24 16:11:57 2023
J 0
(3890 -1335);
PAINT MONO (3890 -1335);
DISPLAY INVISIBLE (3890 -1335);
FORCENOTE
$CDS_IMAGE|F0T_diagram_MB_20211130_rev1-GT_MB_Digram (1).jpg|8985|5483
(1075 2075) 0;
DISPLAY LEFT (1075 2075);
QUIT
